# T6G (Grand Teton) — schematic netlist excerpt (pin names and nets, part order shuffled) for the footprints in the layout excerpt that follows; sources: Cadence DE-HDL packaged netlist, KiCad conversion of 04192023_DAF0TMB3IC0_F0TG_MB_C_brd_V02_OCP.brd

C323  Q_CAP  100UF 4V 20% X6S  pkg C0805  page 334 : A = P0V9_CPU1_RT_2D ; B = GND
C2542  Q_CAP  22UF 4V 20% X6S  pkg C0402  page 70 : A = PVDDCR_SOC_P0 ; B = GND
C2312  Q_CAP  22UF 4V 20% X6S  pkg C0402  page 73 : A = PVDDCR_CPU0_P1 ; B = GND

(kicad_pcb
	(version 20260206)
	(generator "pcbnew")
	(generator_version "10.0")
	(general
		(thickness 1.6)
		(legacy_teardrops no)
	)
	(paper "A4")
	(title_block
		(title "04192023_DAF0TMB3IC0_F0TG_MB_C_brd_V02_OCP.brd")
		(comment 1 "Grand Teton / footprints 5764-5766 of 8354")
	)
	(layers
		(0 "F.Cu" signal "TOP")
		(4 "In1.Cu" signal "GND")
		(6 "In2.Cu" signal "IN1")
		(8 "In3.Cu" signal "GND1")
		(10 "In4.Cu" signal "IN2")
		(12 "In5.Cu" signal "GND2")
		(14 "In6.Cu" signal "IN3")
		(16 "In7.Cu" signal "GND3")
		(18 "In8.Cu" signal "VCC")
		(20 "In9.Cu" signal "VCC1")
		(22 "In10.Cu" signal "GND4")
		(24 "In11.Cu" signal "IN4")
		(26 "In12.Cu" signal "GND5")
		(28 "In13.Cu" signal "IN5")
		(30 "In14.Cu" signal "GND6")
		(32 "In15.Cu" signal "IN6")
		(34 "In16.Cu" signal "GND7")
		(2 "B.Cu" signal "BOTTOM")
		(9 "F.Adhes" user "F.Adhesive")
		(11 "B.Adhes" user "B.Adhesive")
		(13 "F.Paste" user "Package Geometry/Pastemask Top")
		(15 "B.Paste" user "Package Geometry/Pastemask Bottom")
		(5 "F.SilkS" user "Ref Des/Silkscreen Top")
		(7 "B.SilkS" user "Ref Des/Silkscreen Bottom")
		(1 "F.Mask" user "Board Geometry/Soldermask Top")
		(3 "B.Mask" user "Board Geometry/Soldermask Bottom")
		(17 "Dwgs.User" user "User.Drawings")
		(19 "Cmts.User" user "User.Comments")
		(21 "Eco1.User" user "User.Eco1")
		(23 "Eco2.User" user "User.Eco2")
		(25 "Edge.Cuts" user "Board Geometry/Outline")
		(27 "Margin" user)
		(31 "F.CrtYd" user "Package Geometry/Place Bound Top")
		(29 "B.CrtYd" user "Package Geometry/Place Bound Bottom")
		(35 "F.Fab" user "Ref Des/Assembly Top")
		(33 "B.Fab" user "Ref Des/Assembly Bottom")
	)
	(footprint ""
		(layer "B.Cu")
		(at 371.551454 -259.729986)
		(property "Reference" "C2542"
			(at 0 0 0)
			(layer "B.SilkS")
			(hide yes)
			(effects
				(font
					(size 1.27 1.27)
				)
				(justify mirror)
			)
		)
		(property "Value" ""
			(at 0 0 0)
			(layer "B.Fab")
			(effects
				(font
					(size 1.27 1.27)
				)
				(justify mirror)
			)
		)
		(duplicate_pad_numbers_are_jumpers no)
		(fp_line
			(start -0.7874 -0.4064)
			(end -0.7874 0.4064)
			(stroke
				(width 0.1524)
				(type default)
			)
			(layer "B.SilkS")
		)
		(fp_line
			(start -0.7874 0.4064)
			(end 0.7874 0.4064)
			(stroke
				(width 0.1524)
				(type default)
			)
			(layer "B.SilkS")
		)
		(fp_line
			(start 0.7874 -0.4064)
			(end -0.7874 -0.4064)
			(stroke
				(width 0.1524)
				(type default)
			)
			(layer "B.SilkS")
		)
		(fp_line
			(start 0.7874 0.4064)
			(end 0.7874 -0.4064)
			(stroke
				(width 0.1524)
				(type default)
			)
			(layer "B.SilkS")
		)
		(fp_line
			(start -0.67945 -0.3048)
			(end -0.67945 0.3048)
			(stroke
				(width 0.1)
				(type default)
			)
			(layer "B.Fab")
		)
		(fp_line
			(start -0.67945 0.3048)
			(end -0.120396 0.3048)
			(stroke
				(width 0.1)
				(type default)
			)
			(layer "B.Fab")
		)
		(fp_line
			(start -0.12065 -0.3048)
			(end -0.67945 -0.3048)
			(stroke
				(width 0.1)
				(type default)
			)
			(layer "B.Fab")
		)
		(fp_line
			(start -0.12065 -0.2794)
			(end -0.12065 -0.3048)
			(stroke
				(width 0.1)
				(type default)
			)
			(layer "B.Fab")
		)
		(fp_line
			(start -0.120396 0.2794)
			(end 0.12065 0.2794)
			(stroke
				(width 0.1)
				(type default)
			)
			(layer "B.Fab")
		)
		(fp_line
			(start -0.120396 0.3048)
			(end -0.120396 0.2794)
			(stroke
				(width 0.1)
				(type default)
			)
			(layer "B.Fab")
		)
		(fp_line
			(start 0.12065 -0.305054)
			(end 0.12065 -0.2794)
			(stroke
				(width 0.1)
				(type default)
			)
			(layer "B.Fab")
		)
		(fp_line
			(start 0.12065 -0.2794)
			(end -0.12065 -0.2794)
			(stroke
				(width 0.1)
				(type default)
			)
			(layer "B.Fab")
		)
		(fp_line
			(start 0.12065 0.2794)
			(end 0.12065 0.3048)
			(stroke
				(width 0.1)
				(type default)
			)
			(layer "B.Fab")
		)
		(fp_line
			(start 0.12065 0.3048)
			(end 0.67945 0.3048)
			(stroke
				(width 0.1)
				(type default)
			)
			(layer "B.Fab")
		)
		(fp_line
			(start 0.67945 -0.305054)
			(end 0.12065 -0.305054)
			(stroke
				(width 0.1)
				(type default)
			)
			(layer "B.Fab")
		)
		(fp_line
			(start 0.67945 0.3048)
			(end 0.67945 -0.305054)
			(stroke
				(width 0.1)
				(type default)
			)
			(layer "B.Fab")
		)
		(pad "1" smd circle
			(at 0.40005 0 180)
			(size 0 0)
			(layers "B.Cu" "B.Mask" "B.Paste")
			(net "PVDDCR_SOC_P0")
		)
		(pad "2" smd circle
			(at -0.40005 0 180)
			(size 0 0)
			(layers "B.Cu" "B.Mask" "B.Paste")
			(net "GND")
		)
	)
	(footprint ""
		(layer "B.Cu")
		(at 123.611386 -250.892564)
		(property "Reference" "C2312"
			(at 0 0 0)
			(layer "B.SilkS")
			(hide yes)
			(effects
				(font
					(size 1.27 1.27)
				)
				(justify mirror)
			)
		)
		(property "Value" ""
			(at 0 0 0)
			(layer "B.Fab")
			(effects
				(font
					(size 1.27 1.27)
				)
				(justify mirror)
			)
		)
		(duplicate_pad_numbers_are_jumpers no)
		(fp_line
			(start -0.7874 -0.4064)
			(end -0.7874 0.4064)
			(stroke
				(width 0.1524)
				(type default)
			)
			(layer "B.SilkS")
		)
		(fp_line
			(start -0.7874 0.4064)
			(end 0.7874 0.4064)
			(stroke
				(width 0.1524)
				(type default)
			)
			(layer "B.SilkS")
		)
		(fp_line
			(start 0.7874 -0.4064)
			(end -0.7874 -0.4064)
			(stroke
				(width 0.1524)
				(type default)
			)
			(layer "B.SilkS")
		)
		(fp_line
			(start 0.7874 0.4064)
			(end 0.7874 -0.4064)
			(stroke
				(width 0.1524)
				(type default)
			)
			(layer "B.SilkS")
		)
		(fp_line
			(start -0.67945 -0.3048)
			(end -0.67945 0.3048)
			(stroke
				(width 0.1)
				(type default)
			)
			(layer "B.Fab")
		)
		(fp_line
			(start -0.67945 0.3048)
			(end -0.120396 0.3048)
			(stroke
				(width 0.1)
				(type default)
			)
			(layer "B.Fab")
		)
		(fp_line
			(start -0.12065 -0.3048)
			(end -0.67945 -0.3048)
			(stroke
				(width 0.1)
				(type default)
			)
			(layer "B.Fab")
		)
		(fp_line
			(start -0.12065 -0.2794)
			(end -0.12065 -0.3048)
			(stroke
				(width 0.1)
				(type default)
			)
			(layer "B.Fab")
		)
		(fp_line
			(start -0.120396 0.2794)
			(end 0.12065 0.2794)
			(stroke
				(width 0.1)
				(type default)
			)
			(layer "B.Fab")
		)
		(fp_line
			(start -0.120396 0.3048)
			(end -0.120396 0.2794)
			(stroke
				(width 0.1)
				(type default)
			)
			(layer "B.Fab")
		)
		(fp_line
			(start 0.12065 -0.305054)
			(end 0.12065 -0.2794)
			(stroke
				(width 0.1)
				(type default)
			)
			(layer "B.Fab")
		)
		(fp_line
			(start 0.12065 -0.2794)
			(end -0.12065 -0.2794)
			(stroke
				(width 0.1)
				(type default)
			)
			(layer "B.Fab")
		)
		(fp_line
			(start 0.12065 0.2794)
			(end 0.12065 0.3048)
			(stroke
				(width 0.1)
				(type default)
			)
			(layer "B.Fab")
		)
		(fp_line
			(start 0.12065 0.3048)
			(end 0.67945 0.3048)
			(stroke
				(width 0.1)
				(type default)
			)
			(layer "B.Fab")
		)
		(fp_line
			(start 0.67945 -0.305054)
			(end 0.12065 -0.305054)
			(stroke
				(width 0.1)
				(type default)
			)
			(layer "B.Fab")
		)
		(fp_line
			(start 0.67945 0.3048)
			(end 0.67945 -0.305054)
			(stroke
				(width 0.1)
				(type default)
			)
			(layer "B.Fab")
		)
		(pad "1" smd circle
			(at 0.40005 0 180)
			(size 0 0)
			(layers "B.Cu" "B.Mask" "B.Paste")
			(net "PVDDCR_CPU0_P1")
		)
		(pad "2" smd circle
			(at -0.40005 0 180)
			(size 0 0)
			(layers "B.Cu" "B.Mask" "B.Paste")
			(net "GND")
		)
	)
	(footprint ""
		(layer "B.Cu")
		(at 72.462644 -389.673084 90)
		(property "Reference" "C323"
			(at 0 0 90)
			(layer "B.SilkS")
			(hide yes)
			(effects
				(font
					(size 1.27 1.27)
				)
				(justify mirror)
			)
		)
		(property "Value" ""
			(at 0 0 90)
			(layer "B.Fab")
			(effects
				(font
					(size 1.27 1.27)
				)
				(justify mirror)
			)
		)
		(duplicate_pad_numbers_are_jumpers no)
		(fp_line
			(start 1.524 -0.762)
			(end -1.524 -0.762)
			(stroke
				(width 0.1524)
				(type default)
			)
			(layer "B.SilkS")
		)
		(fp_line
			(start -1.524 -0.762)
			(end -1.524 0.762)
			(stroke
				(width 0.1524)
				(type default)
			)
			(layer "B.SilkS")
		)
		(fp_line
			(start 1.524 0.762)
			(end 1.524 -0.762)
			(stroke
				(width 0.1524)
				(type default)
			)
			(layer "B.SilkS")
		)
		(fp_line
			(start -1.524 0.762)
			(end 1.524 0.762)
			(stroke
				(width 0.1524)
				(type default)
			)
			(layer "B.SilkS")
		)
		(fp_line
			(start 1.1049 -0.724916)
			(end 1.1049 0.724916)
			(stroke
				(width 0.1)
				(type default)
			)
			(layer "B.Fab")
		)
		(fp_line
			(start -1.1049 -0.724916)
			(end 1.1049 -0.724916)
			(stroke
				(width 0.1)
				(type default)
			)
			(layer "B.Fab")
		)
		(fp_line
			(start 1.1049 0.724916)
			(end -1.1049 0.724916)
			(stroke
				(width 0.1)
				(type default)
			)
			(layer "B.Fab")
		)
		(fp_line
			(start -1.1049 0.724916)
			(end -1.1049 -0.724916)
			(stroke
				(width 0.1)
				(type default)
			)
			(layer "B.Fab")
		)
		(pad "1" smd rect
			(at 0.889 0 90)
			(size 1.016 1.27)
			(layers "B.Cu" "B.Mask" "B.Paste")
			(net "P0V9_CPU1_RT_2D")
		)
		(pad "2" smd rect
			(at -0.889 0 90)
			(size 1.016 1.27)
			(layers "B.Cu" "B.Mask" "B.Paste")
			(net "GND")
		)
	)
)
